(kicad_pcb
	(version 20260206)
	(generator "pcbnew")
	(generator_version "10.0")
	(general
		(thickness 1.6)
		(legacy_teardrops no)
	)
	(paper "A4")
	(title_block
		(title "baseboard — 13948-1b.1110WZS1818.brd")
		(comment 1 "Honey Badger (Wiwynn) / footprints 849-851 of 2523")
	)
	(layers
		(0 "F.Cu" signal "TOP")
		(4 "In1.Cu" signal "L2GND")
		(6 "In2.Cu" signal "L3")
		(8 "In3.Cu" signal "L4VCC")
		(10 "In4.Cu" signal "L5VCC")
		(12 "In5.Cu" signal "L6")
		(14 "In6.Cu" signal "L7GND")
		(2 "B.Cu" signal "BOTTOM")
		(9 "F.Adhes" user "F.Adhesive")
		(11 "B.Adhes" user "B.Adhesive")
		(13 "F.Paste" user "Package Geometry/Pastemask Top")
		(15 "B.Paste" user "Package Geometry/Pastemask Bottom")
		(5 "F.SilkS" user "Ref Des/Silkscreen Top")
		(7 "B.SilkS" user "Ref Des/Silkscreen Bottom")
		(1 "F.Mask" user "Board Geometry/Soldermask Top")
		(3 "B.Mask" user "Board Geometry/Soldermask Bottom")
		(17 "Dwgs.User" user "User.Drawings")
		(19 "Cmts.User" user "User.Comments")
		(21 "Eco1.User" user "User.Eco1")
		(23 "Eco2.User" user "User.Eco2")
		(25 "Edge.Cuts" user "Board Geometry/Outline")
		(27 "Margin" user)
		(31 "F.CrtYd" user "Package Geometry/Place Bound Top")
		(29 "B.CrtYd" user "Package Geometry/Place Bound Bottom")
		(35 "F.Fab" user "Ref Des/Assembly Top")
		(33 "B.Fab" user "Ref Des/Assembly Bottom")
	)
	(footprint ""
		(layer "F.Cu")
		(at 113.938558 -74.93 -90)
		(property "Reference" "SQ5"
			(at 0 0 270)
			(layer "F.SilkS")
			(hide yes)
			(effects
				(font
					(size 1.27 1.27)
				)
			)
		)
		(property "Value" "AO3400A-GP"
			(at 0.0254 -12.3444 270)
			(unlocked yes)
			(layer "F.Fab")
			(hide yes)
			(effects
				(font
					(size 1.016 1.016)
					(thickness 0.1524)
				)
			)
		)
		(property "Device Type" "SOT23DGS2D8H50"
			(at 0.0254 -14.2494 270)
			(unlocked yes)
			(layer "F.Fab")
			(hide yes)
			(effects
				(font
					(size 1.016 1.016)
					(thickness 0.1524)
				)
			)
		)
		(duplicate_pad_numbers_are_jumpers no)
		(fp_line
			(start -1.7018 0.254)
			(end -1.7018 -0.254)
			(stroke
				(width 0.1524)
				(type default)
			)
			(layer "F.SilkS")
		)
		(fp_line
			(start 1.7018 0.254)
			(end -1.7018 0.254)
			(stroke
				(width 0.1524)
				(type default)
			)
			(layer "F.SilkS")
		)
		(fp_line
			(start -1.7018 -0.254)
			(end 1.7018 -0.254)
			(stroke
				(width 0.1524)
				(type default)
			)
			(layer "F.SilkS")
		)
		(fp_line
			(start 1.7018 -0.254)
			(end 1.7018 0.254)
			(stroke
				(width 0.1524)
				(type default)
			)
			(layer "F.SilkS")
		)
		(fp_rect
			(start -1.778 1.9812)
			(end 1.778 -1.9812)
			(stroke
				(width 0)
				(type default)
			)
			(fill no)
			(layer "F.CrtYd")
		)
		(fp_poly
			(pts
				(xy -1.778 -1.9812) (xy 1.778 -1.9812) (xy 1.778 1.9812) (xy -1.778 1.9812)
			)
			(stroke
				(width 0)
				(type default)
			)
			(fill no)
			(layer "F.Fab")
		)
		(pad "D" smd custom
			(at 0 -1.1176 270)
			(size 0.254 0.254)
			(layers "F.Cu" "F.Mask" "F.Paste")
			(net "EXP_HW_LED_D")
			(options
				(clearance outline)
				(anchor circle)
			)
			(primitives
				(gr_poly
					(pts
						(arc
							(start -0.508 -0.4064)
							(mid -0.448484 -0.550084)
							(end -0.3048 -0.6096)
						)
						(arc
							(start 0.3048 -0.6096)
							(mid 0.448484 -0.550084)
							(end 0.508 -0.4064)
						)
						(arc
							(start 0.508 0.4064)
							(mid 0.448484 0.550084)
							(end 0.3048 0.6096)
						)
						(arc
							(start -0.3048 0.6096)
							(mid -0.448484 0.550084)
							(end -0.508 0.4064)
						)
					)
					(width 0)
					(fill yes)
				)
			)
		)
		(pad "G" smd custom
			(at -1.016 1.1176 270)
			(size 0.254 0.254)
			(layers "F.Cu" "F.Mask" "F.Paste")
			(net "EXP_BLINK_OUT")
			(options
				(clearance outline)
				(anchor circle)
			)
			(primitives
				(gr_poly
					(pts
						(arc
							(start -0.508 -0.4064)
							(mid -0.448484 -0.550084)
							(end -0.3048 -0.6096)
						)
						(arc
							(start 0.3048 -0.6096)
							(mid 0.448484 -0.550084)
							(end 0.508 -0.4064)
						)
						(arc
							(start 0.508 0.4064)
							(mid 0.448484 0.550084)
							(end 0.3048 0.6096)
						)
						(arc
							(start -0.3048 0.6096)
							(mid -0.448484 0.550084)
							(end -0.508 0.4064)
						)
					)
					(width 0)
					(fill yes)
				)
			)
		)
		(pad "S" smd custom
			(at 1.016 1.1176 270)
			(size 0.254 0.254)
			(layers "F.Cu" "F.Mask" "F.Paste")
			(net "GND")
			(options
				(clearance outline)
				(anchor circle)
			)
			(primitives
				(gr_poly
					(pts
						(arc
							(start -0.508 -0.4064)
							(mid -0.448484 -0.550084)
							(end -0.3048 -0.6096)
						)
						(arc
							(start 0.3048 -0.6096)
							(mid 0.448484 -0.550084)
							(end 0.508 -0.4064)
						)
						(arc
							(start 0.508 0.4064)
							(mid 0.448484 0.550084)
							(end 0.3048 0.6096)
						)
						(arc
							(start -0.3048 0.6096)
							(mid -0.448484 0.550084)
							(end -0.508 0.4064)
						)
					)
					(width 0)
					(fill yes)
				)
			)
		)
	)
	(footprint ""
		(layer "F.Cu")
		(at 202.819 -119.634 -90)
		(property "Reference" "R9014"
			(at 0 0 270)
			(layer "F.SilkS")
			(hide yes)
			(effects
				(font
					(size 1.27 1.27)
				)
			)
		)
		(property "Value" "9K53R2F-GP"
			(at 0.064008 -3.993896 270)
			(unlocked yes)
			(layer "F.Fab")
			(hide yes)
			(effects
				(font
					(size 1.016 1.016)
					(thickness 0.1524)
				)
			)
		)
		(property "Device Type" "R402H16"
			(at 0.064008 -5.517896 270)
			(unlocked yes)
			(layer "F.Fab")
			(hide yes)
			(effects
				(font
					(size 1.016 1.016)
					(thickness 0.1524)
				)
			)
		)
		(duplicate_pad_numbers_are_jumpers no)
		(fp_line
			(start -0.508 -0.9398)
			(end -0.508 0.9398)
			(stroke
				(width 0.1524)
				(type default)
			)
			(layer "F.SilkS")
		)
		(fp_line
			(start 0.508 -0.9398)
			(end -0.508 -0.9398)
			(stroke
				(width 0.1524)
				(type default)
			)
			(layer "F.SilkS")
		)
		(fp_rect
			(start -0.508 0.9398)
			(end 0.508 -0.9398)
			(stroke
				(width 0)
				(type default)
			)
			(fill no)
			(layer "F.CrtYd")
		)
		(fp_rect
			(start -0.508 0.9398)
			(end 0.508 -0.9398)
			(stroke
				(width 0)
				(type default)
			)
			(fill no)
			(layer "F.Fab")
		)
		(pad "1" smd custom
			(at 0 -0.4445 270)
			(size 0.1397 0.1397)
			(layers "F.Cu" "F.Mask" "F.Paste")
			(net "P1V5_E_CC_R")
			(options
				(clearance outline)
				(anchor circle)
			)
			(primitives
				(gr_poly
					(pts
						(arc
							(start -0.1778 -0.2794)
							(mid -0.249642 -0.249642)
							(end -0.2794 -0.1778)
						)
						(arc
							(start -0.2794 0.1778)
							(mid -0.249642 0.249642)
							(end -0.1778 0.2794)
						)
						(arc
							(start 0.1778 0.2794)
							(mid 0.249642 0.249642)
							(end 0.2794 0.1778)
						)
						(arc
							(start 0.2794 -0.1778)
							(mid 0.249642 -0.249642)
							(end 0.1778 -0.2794)
						)
					)
					(width 0)
					(fill yes)
				)
			)
		)
		(pad "2" smd custom
			(at 0 0.4445 270)
			(size 0.1397 0.1397)
			(layers "F.Cu" "F.Mask" "F.Paste")
			(net "P1V5_E_VFB")
			(options
				(clearance outline)
				(anchor circle)
			)
			(primitives
				(gr_poly
					(pts
						(arc
							(start -0.1778 -0.2794)
							(mid -0.249642 -0.249642)
							(end -0.2794 -0.1778)
						)
						(arc
							(start -0.2794 0.1778)
							(mid -0.249642 0.249642)
							(end -0.1778 0.2794)
						)
						(arc
							(start 0.1778 0.2794)
							(mid 0.249642 0.249642)
							(end 0.2794 0.1778)
						)
						(arc
							(start 0.2794 -0.1778)
							(mid 0.249642 -0.249642)
							(end 0.1778 -0.2794)
						)
					)
					(width 0)
					(fill yes)
				)
			)
		)
	)
	(footprint ""
		(layer "F.Cu")
		(at 165.1 -113.919 -90)
		(property "Reference" "PR165"
			(at 0 0 270)
			(layer "F.SilkS")
			(hide yes)
			(effects
				(font
					(size 1.27 1.27)
				)
			)
		)
		(property "Value" "10KR2F-2-GP"
			(at 0.064008 -3.993896 270)
			(unlocked yes)
			(layer "F.Fab")
			(hide yes)
			(effects
				(font
					(size 1.016 1.016)
					(thickness 0.1524)
				)
			)
		)
		(property "Device Type" "R402H16"
			(at 0.064008 -5.517896 270)
			(unlocked yes)
			(layer "F.Fab")
			(hide yes)
			(effects
				(font
					(size 1.016 1.016)
					(thickness 0.1524)
				)
			)
		)
		(duplicate_pad_numbers_are_jumpers no)
		(fp_line
			(start -0.508 -0.9398)
			(end -0.508 0.9398)
			(stroke
				(width 0.1524)
				(type default)
			)
			(layer "F.SilkS")
		)
		(fp_line
			(start 0.508 -0.9398)
			(end -0.508 -0.9398)
			(stroke
				(width 0.1524)
				(type default)
			)
			(layer "F.SilkS")
		)
		(fp_rect
			(start -0.508 0.9398)
			(end 0.508 -0.9398)
			(stroke
				(width 0)
				(type default)
			)
			(fill no)
			(layer "F.CrtYd")
		)
		(fp_rect
			(start -0.508 0.9398)
			(end 0.508 -0.9398)
			(stroke
				(width 0)
				(type default)
			)
			(fill no)
			(layer "F.Fab")
		)
		(pad "1" smd custom
			(at 0 -0.4445 270)
			(size 0.1397 0.1397)
			(layers "F.Cu" "F.Mask" "F.Paste")
			(net "P0V9_E_VFB")
			(options
				(clearance outline)
				(anchor circle)
			)
			(primitives
				(gr_poly
					(pts
						(arc
							(start -0.1778 -0.2794)
							(mid -0.249642 -0.249642)
							(end -0.2794 -0.1778)
						)
						(arc
							(start -0.2794 0.1778)
							(mid -0.249642 0.249642)
							(end -0.1778 0.2794)
						)
						(arc
							(start 0.1778 0.2794)
							(mid 0.249642 0.249642)
							(end 0.2794 0.1778)
						)
						(arc
							(start 0.2794 -0.1778)
							(mid 0.249642 -0.249642)
							(end 0.1778 -0.2794)
						)
					)
					(width 0)
					(fill yes)
				)
			)
		)
		(pad "2" smd custom
			(at 0 0.4445 270)
			(size 0.1397 0.1397)
			(layers "F.Cu" "F.Mask" "F.Paste")
			(net "AGND_P0V9_E")
			(options
				(clearance outline)
				(anchor circle)
			)
			(primitives
				(gr_poly
					(pts
						(arc
							(start -0.1778 -0.2794)
							(mid -0.249642 -0.249642)
							(end -0.2794 -0.1778)
						)
						(arc
							(start -0.2794 0.1778)
							(mid -0.249642 0.249642)
							(end -0.1778 0.2794)
						)
						(arc
							(start 0.1778 0.2794)
							(mid 0.249642 0.249642)
							(end 0.2794 0.1778)
						)
						(arc
							(start 0.2794 -0.1778)
							(mid 0.249642 -0.249642)
							(end 0.1778 -0.2794)
						)
					)
					(width 0)
					(fill yes)
				)
			)
		)
	)
)
